(kicad_pcb
	(version 20260206)
	(generator "pcbnew")
	(generator_version "10.0")
	(general
		(thickness 1.6)
		(legacy_teardrops no)
	)
	(paper "A4")
	(title_block
		(title "04192023_DAF0TMB3IC0_F0TG_MB_C_brd_V02_OCP.brd")
		(comment 1 "Grand Teton / footprints 7176-7184 of 8354")
	)
	(layers
		(0 "F.Cu" signal "TOP")
		(4 "In1.Cu" signal "GND")
		(6 "In2.Cu" signal "IN1")
		(8 "In3.Cu" signal "GND1")
		(10 "In4.Cu" signal "IN2")
		(12 "In5.Cu" signal "GND2")
		(14 "In6.Cu" signal "IN3")
		(16 "In7.Cu" signal "GND3")
		(18 "In8.Cu" signal "VCC")
		(20 "In9.Cu" signal "VCC1")
		(22 "In10.Cu" signal "GND4")
		(24 "In11.Cu" signal "IN4")
		(26 "In12.Cu" signal "GND5")
		(28 "In13.Cu" signal "IN5")
		(30 "In14.Cu" signal "GND6")
		(32 "In15.Cu" signal "IN6")
		(34 "In16.Cu" signal "GND7")
		(2 "B.Cu" signal "BOTTOM")
		(9 "F.Adhes" user "F.Adhesive")
		(11 "B.Adhes" user "B.Adhesive")
		(13 "F.Paste" user "Package Geometry/Pastemask Top")
		(15 "B.Paste" user "Package Geometry/Pastemask Bottom")
		(5 "F.SilkS" user "Ref Des/Silkscreen Top")
		(7 "B.SilkS" user "Ref Des/Silkscreen Bottom")
		(1 "F.Mask" user "Board Geometry/Soldermask Top")
		(3 "B.Mask" user "Board Geometry/Soldermask Bottom")
		(17 "Dwgs.User" user "User.Drawings")
		(19 "Cmts.User" user "User.Comments")
		(21 "Eco1.User" user "User.Eco1")
		(23 "Eco2.User" user "User.Eco2")
		(25 "Edge.Cuts" user "Board Geometry/Outline")
		(27 "Margin" user)
		(31 "F.CrtYd" user "Package Geometry/Place Bound Top")
		(29 "B.CrtYd" user "Package Geometry/Place Bound Bottom")
		(35 "F.Fab" user "Ref Des/Assembly Top")
		(33 "B.Fab" user "Ref Des/Assembly Bottom")
	)
	(footprint ""
		(layer "B.Cu")
		(at 356.29596 -257.744976 180)
		(property "Reference" "C2517"
			(at 0 0 0)
			(layer "B.SilkS")
			(hide yes)
			(effects
				(font
					(size 1.27 1.27)
				)
				(justify mirror)
			)
		)
		(property "Value" ""
			(at 0 0 0)
			(layer "B.Fab")
			(effects
				(font
					(size 1.27 1.27)
				)
				(justify mirror)
			)
		)
		(duplicate_pad_numbers_are_jumpers no)
		(fp_line
			(start 0.7874 0.4064)
			(end 0.7874 -0.4064)
			(stroke
				(width 0.1524)
				(type default)
			)
			(layer "B.SilkS")
		)
		(fp_line
			(start 0.7874 -0.4064)
			(end -0.7874 -0.4064)
			(stroke
				(width 0.1524)
				(type default)
			)
			(layer "B.SilkS")
		)
		(fp_line
			(start -0.7874 0.4064)
			(end 0.7874 0.4064)
			(stroke
				(width 0.1524)
				(type default)
			)
			(layer "B.SilkS")
		)
		(fp_line
			(start -0.7874 -0.4064)
			(end -0.7874 0.4064)
			(stroke
				(width 0.1524)
				(type default)
			)
			(layer "B.SilkS")
		)
		(fp_line
			(start 0.67945 0.3048)
			(end 0.67945 -0.305054)
			(stroke
				(width 0.1)
				(type default)
			)
			(layer "B.Fab")
		)
		(fp_line
			(start 0.67945 -0.305054)
			(end 0.12065 -0.305054)
			(stroke
				(width 0.1)
				(type default)
			)
			(layer "B.Fab")
		)
		(fp_line
			(start 0.12065 0.3048)
			(end 0.67945 0.3048)
			(stroke
				(width 0.1)
				(type default)
			)
			(layer "B.Fab")
		)
		(fp_line
			(start 0.12065 0.2794)
			(end 0.12065 0.3048)
			(stroke
				(width 0.1)
				(type default)
			)
			(layer "B.Fab")
		)
		(fp_line
			(start 0.12065 -0.2794)
			(end -0.12065 -0.2794)
			(stroke
				(width 0.1)
				(type default)
			)
			(layer "B.Fab")
		)
		(fp_line
			(start 0.12065 -0.305054)
			(end 0.12065 -0.2794)
			(stroke
				(width 0.1)
				(type default)
			)
			(layer "B.Fab")
		)
		(fp_line
			(start -0.120396 0.3048)
			(end -0.120396 0.2794)
			(stroke
				(width 0.1)
				(type default)
			)
			(layer "B.Fab")
		)
		(fp_line
			(start -0.120396 0.2794)
			(end 0.12065 0.2794)
			(stroke
				(width 0.1)
				(type default)
			)
			(layer "B.Fab")
		)
		(fp_line
			(start -0.12065 -0.2794)
			(end -0.12065 -0.3048)
			(stroke
				(width 0.1)
				(type default)
			)
			(layer "B.Fab")
		)
		(fp_line
			(start -0.12065 -0.3048)
			(end -0.67945 -0.3048)
			(stroke
				(width 0.1)
				(type default)
			)
			(layer "B.Fab")
		)
		(fp_line
			(start -0.67945 0.3048)
			(end -0.120396 0.3048)
			(stroke
				(width 0.1)
				(type default)
			)
			(layer "B.Fab")
		)
		(fp_line
			(start -0.67945 -0.3048)
			(end -0.67945 0.3048)
			(stroke
				(width 0.1)
				(type default)
			)
			(layer "B.Fab")
		)
		(pad "1" smd circle
			(at 0.40005 0)
			(size 0 0)
			(layers "B.Cu" "B.Mask" "B.Paste")
			(net "PVDD18_S5_P0")
		)
		(pad "2" smd circle
			(at -0.40005 0)
			(size 0 0)
			(layers "B.Cu" "B.Mask" "B.Paste")
			(net "GND")
		)
	)
	(footprint ""
		(layer "B.Cu")
		(at 126.478538 -386.766562 90)
		(property "Reference" "C493"
			(at 0 0 90)
			(layer "B.SilkS")
			(hide yes)
			(effects
				(font
					(size 1.27 1.27)
				)
				(justify mirror)
			)
		)
		(property "Value" ""
			(at 0 0 90)
			(layer "B.Fab")
			(effects
				(font
					(size 1.27 1.27)
				)
				(justify mirror)
			)
		)
		(duplicate_pad_numbers_are_jumpers no)
		(fp_line
			(start 0.299974 -0.150114)
			(end -0.299974 -0.150114)
			(stroke
				(width 0.1)
				(type default)
			)
			(layer "B.Fab")
		)
		(fp_line
			(start -0.299974 -0.150114)
			(end -0.299974 0.150114)
			(stroke
				(width 0.1)
				(type default)
			)
			(layer "B.Fab")
		)
		(fp_line
			(start 0.299974 0.150114)
			(end 0.299974 -0.150114)
			(stroke
				(width 0.1)
				(type default)
			)
			(layer "B.Fab")
		)
		(fp_line
			(start -0.299974 0.150114)
			(end 0.299974 0.150114)
			(stroke
				(width 0.1)
				(type default)
			)
			(layer "B.Fab")
		)
		(pad "1" smd rect
			(at 0.2667 0 270)
			(size 0.3048 0.381)
			(layers "B.Cu" "B.Mask" "B.Paste")
			(net "P0V9_CPU1_RT_2D")
		)
		(pad "2" smd rect
			(at -0.2667 0 270)
			(size 0.3048 0.381)
			(layers "B.Cu" "B.Mask" "B.Paste")
			(net "GND")
		)
	)
	(footprint ""
		(layer "B.Cu")
		(at 428.98695 -39.055548)
		(property "Reference" "R1265"
			(at 0 0 0)
			(layer "B.SilkS")
			(hide yes)
			(effects
				(font
					(size 1.27 1.27)
				)
				(justify mirror)
			)
		)
		(property "Value" ""
			(at 0 0 0)
			(layer "B.Fab")
			(effects
				(font
					(size 1.27 1.27)
				)
				(justify mirror)
			)
		)
		(duplicate_pad_numbers_are_jumpers no)
		(fp_line
			(start -0.7874 -0.4064)
			(end -0.7874 0.4064)
			(stroke
				(width 0.1524)
				(type default)
			)
			(layer "B.SilkS")
		)
		(fp_line
			(start -0.7874 0.4064)
			(end 0.7874 0.4064)
			(stroke
				(width 0.1524)
				(type default)
			)
			(layer "B.SilkS")
		)
		(fp_line
			(start 0.7874 -0.4064)
			(end -0.7874 -0.4064)
			(stroke
				(width 0.1524)
				(type default)
			)
			(layer "B.SilkS")
		)
		(fp_line
			(start 0.7874 0.4064)
			(end 0.7874 -0.4064)
			(stroke
				(width 0.1524)
				(type default)
			)
			(layer "B.SilkS")
		)
		(fp_line
			(start -0.67945 -0.3048)
			(end -0.67945 0.3048)
			(stroke
				(width 0.1)
				(type default)
			)
			(layer "B.Fab")
		)
		(fp_line
			(start -0.67945 0.3048)
			(end -0.120396 0.3048)
			(stroke
				(width 0.1)
				(type default)
			)
			(layer "B.Fab")
		)
		(fp_line
			(start -0.12065 -0.3048)
			(end -0.67945 -0.3048)
			(stroke
				(width 0.1)
				(type default)
			)
			(layer "B.Fab")
		)
		(fp_line
			(start -0.12065 -0.2794)
			(end -0.12065 -0.3048)
			(stroke
				(width 0.1)
				(type default)
			)
			(layer "B.Fab")
		)
		(fp_line
			(start -0.120396 0.2794)
			(end 0.12065 0.2794)
			(stroke
				(width 0.1)
				(type default)
			)
			(layer "B.Fab")
		)
		(fp_line
			(start -0.120396 0.3048)
			(end -0.120396 0.2794)
			(stroke
				(width 0.1)
				(type default)
			)
			(layer "B.Fab")
		)
		(fp_line
			(start 0.12065 -0.305054)
			(end 0.12065 -0.2794)
			(stroke
				(width 0.1)
				(type default)
			)
			(layer "B.Fab")
		)
		(fp_line
			(start 0.12065 -0.2794)
			(end -0.12065 -0.2794)
			(stroke
				(width 0.1)
				(type default)
			)
			(layer "B.Fab")
		)
		(fp_line
			(start 0.12065 0.2794)
			(end 0.12065 0.3048)
			(stroke
				(width 0.1)
				(type default)
			)
			(layer "B.Fab")
		)
		(fp_line
			(start 0.12065 0.3048)
			(end 0.67945 0.3048)
			(stroke
				(width 0.1)
				(type default)
			)
			(layer "B.Fab")
		)
		(fp_line
			(start 0.67945 -0.305054)
			(end 0.12065 -0.305054)
			(stroke
				(width 0.1)
				(type default)
			)
			(layer "B.Fab")
		)
		(fp_line
			(start 0.67945 0.3048)
			(end 0.67945 -0.305054)
			(stroke
				(width 0.1)
				(type default)
			)
			(layer "B.Fab")
		)
		(pad "1" smd circle
			(at 0.40005 0 180)
			(size 0 0)
			(layers "B.Cu" "B.Mask" "B.Paste")
			(net "FM_BIOS_USB_RECOVERY")
		)
		(pad "2" smd circle
			(at -0.40005 0 180)
			(size 0 0)
			(layers "B.Cu" "B.Mask" "B.Paste")
			(net "GND")
		)
	)
	(footprint ""
		(layer "B.Cu")
		(at 412.606236 -395.148562 90)
		(property "Reference" "C777"
			(at 0 0 90)
			(layer "B.SilkS")
			(hide yes)
			(effects
				(font
					(size 1.27 1.27)
				)
				(justify mirror)
			)
		)
		(property "Value" ""
			(at 0 0 90)
			(layer "B.Fab")
			(effects
				(font
					(size 1.27 1.27)
				)
				(justify mirror)
			)
		)
		(duplicate_pad_numbers_are_jumpers no)
		(fp_line
			(start 0.299974 -0.150114)
			(end -0.299974 -0.150114)
			(stroke
				(width 0.1)
				(type default)
			)
			(layer "B.Fab")
		)
		(fp_line
			(start -0.299974 -0.150114)
			(end -0.299974 0.150114)
			(stroke
				(width 0.1)
				(type default)
			)
			(layer "B.Fab")
		)
		(fp_line
			(start 0.299974 0.150114)
			(end 0.299974 -0.150114)
			(stroke
				(width 0.1)
				(type default)
			)
			(layer "B.Fab")
		)
		(fp_line
			(start -0.299974 0.150114)
			(end 0.299974 0.150114)
			(stroke
				(width 0.1)
				(type default)
			)
			(layer "B.Fab")
		)
		(pad "1" smd rect
			(at 0.2667 0 270)
			(size 0.3048 0.381)
			(layers "B.Cu" "B.Mask" "B.Paste")
			(net "P1V8_CPU0_RT2_1A")
		)
		(pad "2" smd rect
			(at -0.2667 0 270)
			(size 0.3048 0.381)
			(layers "B.Cu" "B.Mask" "B.Paste")
			(net "GND")
		)
	)
	(footprint ""
		(layer "B.Cu")
		(at 51.118516 -388.011162 -90)
		(property "Reference" "C260"
			(at 0 0 90)
			(layer "B.SilkS")
			(hide yes)
			(effects
				(font
					(size 1.27 1.27)
				)
				(justify mirror)
			)
		)
		(property "Value" ""
			(at 0 0 90)
			(layer "B.Fab")
			(effects
				(font
					(size 1.27 1.27)
				)
				(justify mirror)
			)
		)
		(duplicate_pad_numbers_are_jumpers no)
		(fp_line
			(start -0.299974 0.150114)
			(end 0.299974 0.150114)
			(stroke
				(width 0.1)
				(type default)
			)
			(layer "B.Fab")
		)
		(fp_line
			(start 0.299974 0.150114)
			(end 0.299974 -0.150114)
			(stroke
				(width 0.1)
				(type default)
			)
			(layer "B.Fab")
		)
		(fp_line
			(start -0.299974 -0.150114)
			(end -0.299974 0.150114)
			(stroke
				(width 0.1)
				(type default)
			)
			(layer "B.Fab")
		)
		(fp_line
			(start 0.299974 -0.150114)
			(end -0.299974 -0.150114)
			(stroke
				(width 0.1)
				(type default)
			)
			(layer "B.Fab")
		)
		(pad "1" smd rect
			(at 0.2667 0 90)
			(size 0.3048 0.381)
			(layers "B.Cu" "B.Mask" "B.Paste")
			(net "P0V9_CPU1_RT0_2A")
		)
		(pad "2" smd rect
			(at -0.2667 0 90)
			(size 0.3048 0.381)
			(layers "B.Cu" "B.Mask" "B.Paste")
			(net "GND")
		)
	)
	(footprint ""
		(layer "B.Cu")
		(at 63.118492 -388.011162 -90)
		(property "Reference" "C228"
			(at 0 0 90)
			(layer "B.SilkS")
			(hide yes)
			(effects
				(font
					(size 1.27 1.27)
				)
				(justify mirror)
			)
		)
		(property "Value" ""
			(at 0 0 90)
			(layer "B.Fab")
			(effects
				(font
					(size 1.27 1.27)
				)
				(justify mirror)
			)
		)
		(duplicate_pad_numbers_are_jumpers no)
		(fp_line
			(start -0.299974 0.150114)
			(end 0.299974 0.150114)
			(stroke
				(width 0.1)
				(type default)
			)
			(layer "B.Fab")
		)
		(fp_line
			(start 0.299974 0.150114)
			(end 0.299974 -0.150114)
			(stroke
				(width 0.1)
				(type default)
			)
			(layer "B.Fab")
		)
		(fp_line
			(start -0.299974 -0.150114)
			(end -0.299974 0.150114)
			(stroke
				(width 0.1)
				(type default)
			)
			(layer "B.Fab")
		)
		(fp_line
			(start 0.299974 -0.150114)
			(end -0.299974 -0.150114)
			(stroke
				(width 0.1)
				(type default)
			)
			(layer "B.Fab")
		)
		(pad "1" smd rect
			(at 0.2667 0 90)
			(size 0.3048 0.381)
			(layers "B.Cu" "B.Mask" "B.Paste")
			(net "P0V9_CPU1_RT0_2A")
		)
		(pad "2" smd rect
			(at -0.2667 0 90)
			(size 0.3048 0.381)
			(layers "B.Cu" "B.Mask" "B.Paste")
			(net "GND")
		)
	)
	(footprint ""
		(layer "B.Cu")
		(at 137.492994 -43.37431)
		(property "Reference" "L6001"
			(at 0 0 0)
			(layer "B.SilkS")
			(hide yes)
			(effects
				(font
					(size 1.27 1.27)
				)
				(justify mirror)
			)
		)
		(property "Value" ""
			(at 0 0 0)
			(layer "B.Fab")
			(effects
				(font
					(size 1.27 1.27)
				)
				(justify mirror)
			)
		)
		(duplicate_pad_numbers_are_jumpers no)
		(fp_line
			(start -1.63576 -0.8128)
			(end -1.63576 0.8128)
			(stroke
				(width 0.1524)
				(type default)
			)
			(layer "B.SilkS")
		)
		(fp_line
			(start -1.63576 0.8128)
			(end 1.63576 0.8128)
			(stroke
				(width 0.1524)
				(type default)
			)
			(layer "B.SilkS")
		)
		(fp_line
			(start 1.63576 -0.8128)
			(end -1.63576 -0.8128)
			(stroke
				(width 0.1524)
				(type default)
			)
			(layer "B.SilkS")
		)
		(fp_line
			(start 1.63576 -0.8128)
			(end 1.63576 0.8128)
			(stroke
				(width 0.1524)
				(type default)
			)
			(layer "B.SilkS")
		)
		(fp_line
			(start -1.560576 -0.738632)
			(end 1.56083 -0.738632)
			(stroke
				(width 0.1)
				(type default)
			)
			(layer "B.Fab")
		)
		(fp_line
			(start -1.560576 0.7366)
			(end -1.560576 -0.738632)
			(stroke
				(width 0.1)
				(type default)
			)
			(layer "B.Fab")
		)
		(fp_line
			(start -1.524 0.7366)
			(end -1.560576 0.7366)
			(stroke
				(width 0.1)
				(type default)
			)
			(layer "B.Fab")
		)
		(fp_line
			(start 1.524 0.7366)
			(end -1.524 0.7366)
			(stroke
				(width 0.1)
				(type default)
			)
			(layer "B.Fab")
		)
		(fp_line
			(start 1.56083 -0.738632)
			(end 1.56083 0.7366)
			(stroke
				(width 0.1)
				(type default)
			)
			(layer "B.Fab")
		)
		(fp_line
			(start 1.56083 0.7366)
			(end 1.524 0.7366)
			(stroke
				(width 0.1)
				(type default)
			)
			(layer "B.Fab")
		)
		(pad "1" smd rect
			(at 0.94996 0)
			(size 1.1176 1.3716)
			(layers "B.Cu" "B.Mask" "B.Paste")
			(net "P1V2_AUX")
		)
		(pad "2" smd rect
			(at -0.94996 0)
			(size 1.1176 1.3716)
			(layers "B.Cu" "B.Mask" "B.Paste")
			(net "P1V2_CPU0_USB_DVDD12")
		)
	)
	(footprint ""
		(layer "B.Cu")
		(at 385.129278 -144.266158)
		(property "Reference" "PR307"
			(at 0 0 0)
			(layer "B.SilkS")
			(hide yes)
			(effects
				(font
					(size 1.27 1.27)
				)
				(justify mirror)
			)
		)
		(property "Value" ""
			(at 0 0 0)
			(layer "B.Fab")
			(effects
				(font
					(size 1.27 1.27)
				)
				(justify mirror)
			)
		)
		(duplicate_pad_numbers_are_jumpers no)
		(fp_line
			(start -0.7874 -0.4064)
			(end -0.7874 0.4064)
			(stroke
				(width 0.1524)
				(type default)
			)
			(layer "B.SilkS")
		)
		(fp_line
			(start -0.7874 0.4064)
			(end 0.7874 0.4064)
			(stroke
				(width 0.1524)
				(type default)
			)
			(layer "B.SilkS")
		)
		(fp_line
			(start 0.7874 -0.4064)
			(end -0.7874 -0.4064)
			(stroke
				(width 0.1524)
				(type default)
			)
			(layer "B.SilkS")
		)
		(fp_line
			(start 0.7874 0.4064)
			(end 0.7874 -0.4064)
			(stroke
				(width 0.1524)
				(type default)
			)
			(layer "B.SilkS")
		)
		(fp_line
			(start -0.67945 -0.3048)
			(end -0.67945 0.3048)
			(stroke
				(width 0.1)
				(type default)
			)
			(layer "B.Fab")
		)
		(fp_line
			(start -0.67945 0.3048)
			(end -0.120396 0.3048)
			(stroke
				(width 0.1)
				(type default)
			)
			(layer "B.Fab")
		)
		(fp_line
			(start -0.12065 -0.3048)
			(end -0.67945 -0.3048)
			(stroke
				(width 0.1)
				(type default)
			)
			(layer "B.Fab")
		)
		(fp_line
			(start -0.12065 -0.2794)
			(end -0.12065 -0.3048)
			(stroke
				(width 0.1)
				(type default)
			)
			(layer "B.Fab")
		)
		(fp_line
			(start -0.120396 0.2794)
			(end 0.12065 0.2794)
			(stroke
				(width 0.1)
				(type default)
			)
			(layer "B.Fab")
		)
		(fp_line
			(start -0.120396 0.3048)
			(end -0.120396 0.2794)
			(stroke
				(width 0.1)
				(type default)
			)
			(layer "B.Fab")
		)
		(fp_line
			(start 0.12065 -0.305054)
			(end 0.12065 -0.2794)
			(stroke
				(width 0.1)
				(type default)
			)
			(layer "B.Fab")
		)
		(fp_line
			(start 0.12065 -0.2794)
			(end -0.12065 -0.2794)
			(stroke
				(width 0.1)
				(type default)
			)
			(layer "B.Fab")
		)
		(fp_line
			(start 0.12065 0.2794)
			(end 0.12065 0.3048)
			(stroke
				(width 0.1)
				(type default)
			)
			(layer "B.Fab")
		)
		(fp_line
			(start 0.12065 0.3048)
			(end 0.67945 0.3048)
			(stroke
				(width 0.1)
				(type default)
			)
			(layer "B.Fab")
		)
		(fp_line
			(start 0.67945 -0.305054)
			(end 0.12065 -0.305054)
			(stroke
				(width 0.1)
				(type default)
			)
			(layer "B.Fab")
		)
		(fp_line
			(start 0.67945 0.3048)
			(end 0.67945 -0.305054)
			(stroke
				(width 0.1)
				(type default)
			)
			(layer "B.Fab")
		)
		(pad "1" smd circle
			(at 0.40005 0 180)
			(size 0 0)
			(layers "B.Cu" "B.Mask" "B.Paste")
			(net "VSENSE_PVDDCR_SOC_P0_DP")
		)
		(pad "2" smd circle
			(at -0.40005 0 180)
			(size 0 0)
			(layers "B.Cu" "B.Mask" "B.Paste")
			(net "VSENSE_PVDDCR_SOC_P0_VSEN1")
		)
	)
	(footprint ""
		(layer "B.Cu")
		(at 368.334798 -424.372786 180)
		(property "Reference" "R687"
			(at 0 0 0)
			(layer "B.SilkS")
			(hide yes)
			(effects
				(font
					(size 1.27 1.27)
				)
				(justify mirror)
			)
		)
		(property "Value" ""
			(at 0 0 0)
			(layer "B.Fab")
			(effects
				(font
					(size 1.27 1.27)
				)
				(justify mirror)
			)
		)
		(duplicate_pad_numbers_are_jumpers no)
		(fp_line
			(start 0.32512 0.175006)
			(end 0.32512 -0.175006)
			(stroke
				(width 0.1)
				(type default)
			)
			(layer "B.Fab")
		)
		(fp_line
			(start 0.32512 -0.175006)
			(end -0.32512 -0.175006)
			(stroke
				(width 0.1)
				(type default)
			)
			(layer "B.Fab")
		)
		(fp_line
			(start -0.32512 0.175006)
			(end 0.32512 0.175006)
			(stroke
				(width 0.1)
				(type default)
			)
			(layer "B.Fab")
		)
		(fp_line
			(start -0.32512 -0.175006)
			(end -0.32512 0.175006)
			(stroke
				(width 0.1)
				(type default)
			)
			(layer "B.Fab")
		)
		(pad "1" smd rect
			(at 0.2667 0)
			(size 0.3048 0.381)
			(layers "B.Cu" "B.Mask" "B.Paste")
			(net "SMB_RT_CPU0_P3_ROM_R_SCL")
		)
		(pad "2" smd rect
			(at -0.2667 0 180)
			(size 0.3048 0.381)
			(layers "B.Cu" "B.Mask" "B.Paste")
			(net "SMB_RT_CPU0_P3_ROM_SCL")
		)
	)
)
